(kicad_pcb
	(version 20260206)
	(generator "pcbnew")
	(generator_version "10.0")
	(general
		(thickness 1.6)
		(legacy_teardrops no)
	)
	(paper "A4")
	(title_block
		(title "v1-pdb — T6M_PDB_D_0927_0900.brd")
		(comment 1 "Open CloudServer (Microsoft) / footprints 272-281 of 321")
	)
	(layers
		(0 "F.Cu" signal "TOP")
		(4 "In1.Cu" signal "GND")
		(6 "In2.Cu" signal "IN1")
		(8 "In3.Cu" signal "VCC")
		(10 "In4.Cu" signal "VCC1")
		(12 "In5.Cu" signal "IN2")
		(14 "In6.Cu" signal "GND1")
		(2 "B.Cu" signal "BOTTOM")
		(9 "F.Adhes" user "F.Adhesive")
		(11 "B.Adhes" user "B.Adhesive")
		(13 "F.Paste" user "Package Geometry/Pastemask Top")
		(15 "B.Paste" user "Package Geometry/Pastemask Bottom")
		(5 "F.SilkS" user "Ref Des/Silkscreen Top")
		(7 "B.SilkS" user "Ref Des/Silkscreen Bottom")
		(1 "F.Mask" user "Board Geometry/Soldermask Top")
		(3 "B.Mask" user "Board Geometry/Soldermask Bottom")
		(17 "Dwgs.User" user "User.Drawings")
		(19 "Cmts.User" user "User.Comments")
		(21 "Eco1.User" user "User.Eco1")
		(23 "Eco2.User" user "User.Eco2")
		(25 "Edge.Cuts" user "Board Geometry/Outline")
		(27 "Margin" user)
		(31 "F.CrtYd" user "Package Geometry/Place Bound Top")
		(29 "B.CrtYd" user "Package Geometry/Place Bound Bottom")
		(35 "F.Fab" user "Ref Des/Assembly Top")
		(33 "B.Fab" user "Ref Des/Assembly Bottom")
	)
	(footprint ""
		(layer "F.Cu")
		(at 39.874952 -461.170274 180)
		(property "Reference" "R23"
			(at -1.982978 -0.229108 0)
			(unlocked yes)
			(layer "F.SilkS")
			(effects
				(font
					(size 0.7874 0.5842)
					(thickness 0.1524)
				)
				(justify left)
			)
		)
		(property "Value" ""
			(at 0 0 180)
			(layer "F.Fab")
			(effects
				(font
					(size 1.27 1.27)
				)
			)
		)
		(duplicate_pad_numbers_are_jumpers no)
		(fp_line
			(start 0.7874 0.4064)
			(end -0.7874 0.4064)
			(stroke
				(width 0.1524)
				(type default)
			)
			(layer "F.SilkS")
		)
		(fp_line
			(start 0.7874 -0.4064)
			(end 0.7874 0.4064)
			(stroke
				(width 0.1524)
				(type default)
			)
			(layer "F.SilkS")
		)
		(fp_line
			(start -0.7874 0.4064)
			(end -0.7874 -0.4064)
			(stroke
				(width 0.1524)
				(type default)
			)
			(layer "F.SilkS")
		)
		(fp_line
			(start -0.7874 -0.4064)
			(end 0.7874 -0.4064)
			(stroke
				(width 0.1524)
				(type default)
			)
			(layer "F.SilkS")
		)
		(fp_poly
			(pts
				(xy -0.508 0.2794) (xy -0.508 0.2286) (xy -0.635 0.2286) (xy -0.635 -0.254) (xy -0.5334 -0.254)
				(xy -0.5334 -0.2794) (xy 0.5334 -0.2794) (xy 0.5334 -0.254) (xy 0.635 -0.254) (xy 0.635 0.254) (xy 0.5334 0.254)
				(xy 0.5334 0.2794)
			)
			(stroke
				(width 0)
				(type default)
			)
			(fill no)
			(layer "F.CrtYd")
		)
		(pad "1" smd rect
			(at 0.40005 0 180)
			(size 0.4572 0.508)
			(layers "F.Cu" "F.Mask" "F.Paste")
			(net "PSU6_AD0")
		)
		(pad "2" smd rect
			(at -0.40005 0 180)
			(size 0.4572 0.508)
			(layers "F.Cu" "F.Mask" "F.Paste")
			(net "GND")
		)
	)
	(footprint ""
		(layer "F.Cu")
		(at 25.804876 -369.095274)
		(property "Reference" "R138"
			(at -3.886962 -0.631952 0)
			(unlocked yes)
			(layer "F.SilkS")
			(effects
				(font
					(size 0.7874 0.5842)
					(thickness 0.1524)
				)
				(justify left)
			)
		)
		(property "Value" ""
			(at 0 0 0)
			(layer "F.Fab")
			(effects
				(font
					(size 1.27 1.27)
				)
			)
		)
		(duplicate_pad_numbers_are_jumpers no)
		(fp_line
			(start -0.7874 -0.4064)
			(end 0.7874 -0.4064)
			(stroke
				(width 0.1524)
				(type default)
			)
			(layer "F.SilkS")
		)
		(fp_line
			(start -0.7874 0.4064)
			(end -0.7874 -0.4064)
			(stroke
				(width 0.1524)
				(type default)
			)
			(layer "F.SilkS")
		)
		(fp_line
			(start 0.7874 -0.4064)
			(end 0.7874 0.4064)
			(stroke
				(width 0.1524)
				(type default)
			)
			(layer "F.SilkS")
		)
		(fp_line
			(start 0.7874 0.4064)
			(end -0.7874 0.4064)
			(stroke
				(width 0.1524)
				(type default)
			)
			(layer "F.SilkS")
		)
		(fp_poly
			(pts
				(xy -0.508 0.2794) (xy -0.508 0.2286) (xy -0.635 0.2286) (xy -0.635 -0.254) (xy -0.5334 -0.254)
				(xy -0.5334 -0.2794) (xy 0.5334 -0.2794) (xy 0.5334 -0.254) (xy 0.635 -0.254) (xy 0.635 0.254) (xy 0.5334 0.254)
				(xy 0.5334 0.2794)
			)
			(stroke
				(width 0)
				(type default)
			)
			(fill no)
			(layer "F.CrtYd")
		)
		(pad "1" smd rect
			(at 0.40005 0)
			(size 0.4572 0.508)
			(layers "F.Cu" "F.Mask" "F.Paste")
			(net "PSU5_CSAHRE")
		)
		(pad "2" smd rect
			(at -0.40005 0)
			(size 0.4572 0.508)
			(layers "F.Cu" "F.Mask" "F.Paste")
			(net "PSU_CSAHRE")
		)
	)
	(footprint ""
		(layer "F.Cu")
		(at 39.461948 -199.56907 -90)
		(property "Reference" "R94"
			(at -0.904494 -3.072892 90)
			(unlocked yes)
			(layer "F.SilkS")
			(effects
				(font
					(size 0.7874 0.5842)
					(thickness 0.1524)
				)
				(justify left)
			)
		)
		(property "Value" ""
			(at 0 0 270)
			(layer "F.Fab")
			(effects
				(font
					(size 1.27 1.27)
				)
			)
		)
		(duplicate_pad_numbers_are_jumpers no)
		(fp_line
			(start -0.7874 0.4064)
			(end -0.7874 -0.4064)
			(stroke
				(width 0.1524)
				(type default)
			)
			(layer "F.SilkS")
		)
		(fp_line
			(start 0.7874 0.4064)
			(end -0.7874 0.4064)
			(stroke
				(width 0.1524)
				(type default)
			)
			(layer "F.SilkS")
		)
		(fp_line
			(start -0.7874 -0.4064)
			(end 0.7874 -0.4064)
			(stroke
				(width 0.1524)
				(type default)
			)
			(layer "F.SilkS")
		)
		(fp_line
			(start 0.7874 -0.4064)
			(end 0.7874 0.4064)
			(stroke
				(width 0.1524)
				(type default)
			)
			(layer "F.SilkS")
		)
		(fp_poly
			(pts
				(xy -0.508 0.2794) (xy -0.508 0.2286) (xy -0.635 0.2286) (xy -0.635 -0.254) (xy -0.5334 -0.254)
				(xy -0.5334 -0.2794) (xy 0.5334 -0.2794) (xy 0.5334 -0.254) (xy 0.635 -0.254) (xy 0.635 0.254) (xy 0.5334 0.254)
				(xy 0.5334 0.2794)
			)
			(stroke
				(width 0)
				(type default)
			)
			(fill no)
			(layer "F.CrtYd")
		)
		(pad "1" smd rect
			(at 0.40005 0 270)
			(size 0.4572 0.508)
			(layers "F.Cu" "F.Mask" "F.Paste")
			(net "PSU3_REMOTE_P")
		)
		(pad "2" smd rect
			(at -0.40005 0 270)
			(size 0.4572 0.508)
			(layers "F.Cu" "F.Mask" "F.Paste")
			(net "PSU3_REMOTE_R_P")
		)
	)
	(footprint ""
		(layer "F.Cu")
		(at 71.11746 -370.601748 -90)
		(property "Reference" "C59"
			(at -2.675128 -0.117856 90)
			(unlocked yes)
			(layer "F.SilkS")
			(effects
				(font
					(size 0.7874 0.5842)
					(thickness 0.1524)
				)
				(justify left)
			)
		)
		(property "Value" ""
			(at 0 0 270)
			(layer "F.Fab")
			(effects
				(font
					(size 1.27 1.27)
				)
			)
		)
		(duplicate_pad_numbers_are_jumpers no)
		(fp_line
			(start -0.7874 0.4064)
			(end -0.7874 -0.4064)
			(stroke
				(width 0.1524)
				(type default)
			)
			(layer "F.SilkS")
		)
		(fp_line
			(start 0.7874 0.4064)
			(end -0.7874 0.4064)
			(stroke
				(width 0.1524)
				(type default)
			)
			(layer "F.SilkS")
		)
		(fp_line
			(start 0 0.381)
			(end 0 -0.381)
			(stroke
				(width 0.1524)
				(type default)
			)
			(layer "F.SilkS")
		)
		(fp_line
			(start -0.7874 -0.4064)
			(end 0.7874 -0.4064)
			(stroke
				(width 0.1524)
				(type default)
			)
			(layer "F.SilkS")
		)
		(fp_line
			(start 0.7874 -0.4064)
			(end 0.7874 0.4064)
			(stroke
				(width 0.1524)
				(type default)
			)
			(layer "F.SilkS")
		)
		(fp_poly
			(pts
				(xy -0.5334 0.254) (xy -0.635 0.254) (xy -0.635 0.2286) (xy -0.635 -0.254) (xy -0.5334 -0.254) (xy -0.5334 -0.2794)
				(xy 0.5334 -0.2794) (xy 0.5334 -0.254) (xy 0.635 -0.254) (xy 0.635 0.254) (xy 0.5334 0.254) (xy 0.5334 0.2794)
				(xy -0.508 0.2794) (xy -0.5334 0.2794)
			)
			(stroke
				(width 0)
				(type default)
			)
			(fill no)
			(layer "F.CrtYd")
		)
		(pad "1" smd rect
			(at 0.40005 0 270)
			(size 0.4572 0.508)
			(layers "F.Cu" "F.Mask" "F.Paste")
			(net "P12V")
		)
		(pad "2" smd rect
			(at -0.40005 0 270)
			(size 0.4572 0.508)
			(layers "F.Cu" "F.Mask" "F.Paste")
			(net "GND")
		)
	)
	(footprint ""
		(layer "F.Cu")
		(at 81.29143 -504.305824 -90)
		(property "Reference" "C79"
			(at -2.739136 0.063246 90)
			(unlocked yes)
			(layer "F.SilkS")
			(effects
				(font
					(size 0.7874 0.5842)
					(thickness 0.1524)
				)
				(justify left)
			)
		)
		(property "Value" ""
			(at 0 0 270)
			(layer "F.Fab")
			(effects
				(font
					(size 1.27 1.27)
				)
			)
		)
		(duplicate_pad_numbers_are_jumpers no)
		(fp_line
			(start -0.7874 0.4064)
			(end -0.7874 -0.4064)
			(stroke
				(width 0.1524)
				(type default)
			)
			(layer "F.SilkS")
		)
		(fp_line
			(start 0.7874 0.4064)
			(end -0.7874 0.4064)
			(stroke
				(width 0.1524)
				(type default)
			)
			(layer "F.SilkS")
		)
		(fp_line
			(start 0 0.381)
			(end 0 -0.381)
			(stroke
				(width 0.1524)
				(type default)
			)
			(layer "F.SilkS")
		)
		(fp_line
			(start -0.7874 -0.4064)
			(end 0.7874 -0.4064)
			(stroke
				(width 0.1524)
				(type default)
			)
			(layer "F.SilkS")
		)
		(fp_line
			(start 0.7874 -0.4064)
			(end 0.7874 0.4064)
			(stroke
				(width 0.1524)
				(type default)
			)
			(layer "F.SilkS")
		)
		(fp_poly
			(pts
				(xy -0.5334 0.254) (xy -0.635 0.254) (xy -0.635 0.2286) (xy -0.635 -0.254) (xy -0.5334 -0.254) (xy -0.5334 -0.2794)
				(xy 0.5334 -0.2794) (xy 0.5334 -0.254) (xy 0.635 -0.254) (xy 0.635 0.254) (xy 0.5334 0.254) (xy 0.5334 0.2794)
				(xy -0.508 0.2794) (xy -0.5334 0.2794)
			)
			(stroke
				(width 0)
				(type default)
			)
			(fill no)
			(layer "F.CrtYd")
		)
		(pad "1" smd rect
			(at 0.40005 0 270)
			(size 0.4572 0.508)
			(layers "F.Cu" "F.Mask" "F.Paste")
			(net "P12V")
		)
		(pad "2" smd rect
			(at -0.40005 0 270)
			(size 0.4572 0.508)
			(layers "F.Cu" "F.Mask" "F.Paste")
			(net "GND")
		)
	)
	(footprint ""
		(layer "F.Cu")
		(at 71.96836 -175.945546 90)
		(property "Reference" "C32"
			(at -4.154678 0.383032 90)
			(unlocked yes)
			(layer "F.SilkS")
			(effects
				(font
					(size 0.7874 0.5842)
					(thickness 0.1524)
				)
				(justify left)
			)
		)
		(property "Value" ""
			(at 0 0 90)
			(layer "F.Fab")
			(effects
				(font
					(size 1.27 1.27)
				)
			)
		)
		(duplicate_pad_numbers_are_jumpers no)
		(fp_line
			(start 0.7874 -0.4064)
			(end 0.7874 0.4064)
			(stroke
				(width 0.1524)
				(type default)
			)
			(layer "F.SilkS")
		)
		(fp_line
			(start -0.7874 -0.4064)
			(end 0.7874 -0.4064)
			(stroke
				(width 0.1524)
				(type default)
			)
			(layer "F.SilkS")
		)
		(fp_line
			(start 0 0.381)
			(end 0 -0.381)
			(stroke
				(width 0.1524)
				(type default)
			)
			(layer "F.SilkS")
		)
		(fp_line
			(start 0.7874 0.4064)
			(end -0.7874 0.4064)
			(stroke
				(width 0.1524)
				(type default)
			)
			(layer "F.SilkS")
		)
		(fp_line
			(start -0.7874 0.4064)
			(end -0.7874 -0.4064)
			(stroke
				(width 0.1524)
				(type default)
			)
			(layer "F.SilkS")
		)
		(fp_poly
			(pts
				(xy -0.5334 0.254) (xy -0.635 0.254) (xy -0.635 0.2286) (xy -0.635 -0.254) (xy -0.5334 -0.254) (xy -0.5334 -0.2794)
				(xy 0.5334 -0.2794) (xy 0.5334 -0.254) (xy 0.635 -0.254) (xy 0.635 0.254) (xy 0.5334 0.254) (xy 0.5334 0.2794)
				(xy -0.508 0.2794) (xy -0.5334 0.2794)
			)
			(stroke
				(width 0)
				(type default)
			)
			(fill no)
			(layer "F.CrtYd")
		)
		(pad "1" smd rect
			(at 0.40005 0 90)
			(size 0.4572 0.508)
			(layers "F.Cu" "F.Mask" "F.Paste")
			(net "P12V")
		)
		(pad "2" smd rect
			(at -0.40005 0 90)
			(size 0.4572 0.508)
			(layers "F.Cu" "F.Mask" "F.Paste")
			(net "GND")
		)
	)
	(footprint ""
		(layer "F.Cu")
		(at 75.316842 -42.631106 90)
		(property "Reference" "C11"
			(at -1.090422 4.586478 90)
			(unlocked yes)
			(layer "F.SilkS")
			(effects
				(font
					(size 0.7874 0.5842)
					(thickness 0.1524)
				)
				(justify left)
			)
		)
		(property "Value" ""
			(at 0 0 90)
			(layer "F.Fab")
			(effects
				(font
					(size 1.27 1.27)
				)
			)
		)
		(duplicate_pad_numbers_are_jumpers no)
		(fp_line
			(start 0.7874 -0.4064)
			(end 0.7874 0.4064)
			(stroke
				(width 0.1524)
				(type default)
			)
			(layer "F.SilkS")
		)
		(fp_line
			(start -0.7874 -0.4064)
			(end 0.7874 -0.4064)
			(stroke
				(width 0.1524)
				(type default)
			)
			(layer "F.SilkS")
		)
		(fp_line
			(start 0 0.381)
			(end 0 -0.381)
			(stroke
				(width 0.1524)
				(type default)
			)
			(layer "F.SilkS")
		)
		(fp_line
			(start 0.7874 0.4064)
			(end -0.7874 0.4064)
			(stroke
				(width 0.1524)
				(type default)
			)
			(layer "F.SilkS")
		)
		(fp_line
			(start -0.7874 0.4064)
			(end -0.7874 -0.4064)
			(stroke
				(width 0.1524)
				(type default)
			)
			(layer "F.SilkS")
		)
		(fp_poly
			(pts
				(xy -0.5334 0.254) (xy -0.635 0.254) (xy -0.635 0.2286) (xy -0.635 -0.254) (xy -0.5334 -0.254) (xy -0.5334 -0.2794)
				(xy 0.5334 -0.2794) (xy 0.5334 -0.254) (xy 0.635 -0.254) (xy 0.635 0.254) (xy 0.5334 0.254) (xy 0.5334 0.2794)
				(xy -0.508 0.2794) (xy -0.5334 0.2794)
			)
			(stroke
				(width 0)
				(type default)
			)
			(fill no)
			(layer "F.CrtYd")
		)
		(pad "1" smd rect
			(at 0.40005 0 90)
			(size 0.4572 0.508)
			(layers "F.Cu" "F.Mask" "F.Paste")
			(net "P12V")
		)
		(pad "2" smd rect
			(at -0.40005 0 90)
			(size 0.4572 0.508)
			(layers "F.Cu" "F.Mask" "F.Paste")
			(net "GND")
		)
	)
	(footprint ""
		(layer "F.Cu")
		(at 71.423276 -237.708694 -90)
		(property "Reference" "C37"
			(at 0.73406 -3.745992 90)
			(unlocked yes)
			(layer "F.SilkS")
			(effects
				(font
					(size 0.7874 0.5842)
					(thickness 0.1524)
				)
				(justify left)
			)
		)
		(property "Value" ""
			(at 0 0 270)
			(layer "F.Fab")
			(effects
				(font
					(size 1.27 1.27)
				)
			)
		)
		(duplicate_pad_numbers_are_jumpers no)
		(fp_line
			(start -0.7874 0.4064)
			(end -0.7874 -0.4064)
			(stroke
				(width 0.1524)
				(type default)
			)
			(layer "F.SilkS")
		)
		(fp_line
			(start 0.7874 0.4064)
			(end -0.7874 0.4064)
			(stroke
				(width 0.1524)
				(type default)
			)
			(layer "F.SilkS")
		)
		(fp_line
			(start 0 0.381)
			(end 0 -0.381)
			(stroke
				(width 0.1524)
				(type default)
			)
			(layer "F.SilkS")
		)
		(fp_line
			(start -0.7874 -0.4064)
			(end 0.7874 -0.4064)
			(stroke
				(width 0.1524)
				(type default)
			)
			(layer "F.SilkS")
		)
		(fp_line
			(start 0.7874 -0.4064)
			(end 0.7874 0.4064)
			(stroke
				(width 0.1524)
				(type default)
			)
			(layer "F.SilkS")
		)
		(fp_poly
			(pts
				(xy -0.5334 0.254) (xy -0.635 0.254) (xy -0.635 0.2286) (xy -0.635 -0.254) (xy -0.5334 -0.254) (xy -0.5334 -0.2794)
				(xy 0.5334 -0.2794) (xy 0.5334 -0.254) (xy 0.635 -0.254) (xy 0.635 0.254) (xy 0.5334 0.254) (xy 0.5334 0.2794)
				(xy -0.508 0.2794) (xy -0.5334 0.2794)
			)
			(stroke
				(width 0)
				(type default)
			)
			(fill no)
			(layer "F.CrtYd")
		)
		(pad "1" smd rect
			(at 0.40005 0 270)
			(size 0.4572 0.508)
			(layers "F.Cu" "F.Mask" "F.Paste")
			(net "P12V")
		)
		(pad "2" smd rect
			(at -0.40005 0 270)
			(size 0.4572 0.508)
			(layers "F.Cu" "F.Mask" "F.Paste")
			(net "GND")
		)
	)
	(footprint ""
		(layer "F.Cu")
		(at 68.697602 -120.313958 180)
		(property "Reference" "R115"
			(at 2.566162 1.311148 0)
			(unlocked yes)
			(layer "F.SilkS")
			(effects
				(font
					(size 0.7874 0.5842)
					(thickness 0.1524)
				)
				(justify left)
			)
		)
		(property "Value" ""
			(at 0 0 180)
			(layer "F.Fab")
			(effects
				(font
					(size 1.27 1.27)
				)
			)
		)
		(duplicate_pad_numbers_are_jumpers no)
		(fp_line
			(start 0.7874 0.4064)
			(end -0.7874 0.4064)
			(stroke
				(width 0.1524)
				(type default)
			)
			(layer "F.SilkS")
		)
		(fp_line
			(start 0.7874 -0.4064)
			(end 0.7874 0.4064)
			(stroke
				(width 0.1524)
				(type default)
			)
			(layer "F.SilkS")
		)
		(fp_line
			(start -0.7874 0.4064)
			(end -0.7874 -0.4064)
			(stroke
				(width 0.1524)
				(type default)
			)
			(layer "F.SilkS")
		)
		(fp_line
			(start -0.7874 -0.4064)
			(end 0.7874 -0.4064)
			(stroke
				(width 0.1524)
				(type default)
			)
			(layer "F.SilkS")
		)
		(fp_poly
			(pts
				(xy -0.508 0.2794) (xy -0.508 0.2286) (xy -0.635 0.2286) (xy -0.635 -0.254) (xy -0.5334 -0.254)
				(xy -0.5334 -0.2794) (xy 0.5334 -0.2794) (xy 0.5334 -0.254) (xy 0.635 -0.254) (xy 0.635 0.254) (xy 0.5334 0.254)
				(xy 0.5334 0.2794)
			)
			(stroke
				(width 0)
				(type default)
			)
			(fill no)
			(layer "F.CrtYd")
		)
		(pad "1" smd rect
			(at 0.40005 0 180)
			(size 0.4572 0.508)
			(layers "F.Cu" "F.Mask" "F.Paste")
			(net "PSU2_REMOTE_R2_P")
		)
		(pad "2" smd rect
			(at -0.40005 0 180)
			(size 0.4572 0.508)
			(layers "F.Cu" "F.Mask" "F.Paste")
			(net "P12V")
		)
	)
	(footprint ""
		(layer "F.Cu")
		(at 25.857708 -364.246414)
		(property "Reference" "R78"
			(at -3.917442 -0.225298 0)
			(unlocked yes)
			(layer "F.SilkS")
			(effects
				(font
					(size 0.7874 0.5842)
					(thickness 0.1524)
				)
				(justify left)
			)
		)
		(property "Value" ""
			(at 0 0 0)
			(layer "F.Fab")
			(effects
				(font
					(size 1.27 1.27)
				)
			)
		)
		(duplicate_pad_numbers_are_jumpers no)
		(fp_line
			(start -0.7874 -0.4064)
			(end 0.7874 -0.4064)
			(stroke
				(width 0.1524)
				(type default)
			)
			(layer "F.SilkS")
		)
		(fp_line
			(start -0.7874 0.4064)
			(end -0.7874 -0.4064)
			(stroke
				(width 0.1524)
				(type default)
			)
			(layer "F.SilkS")
		)
		(fp_line
			(start 0.7874 -0.4064)
			(end 0.7874 0.4064)
			(stroke
				(width 0.1524)
				(type default)
			)
			(layer "F.SilkS")
		)
		(fp_line
			(start 0.7874 0.4064)
			(end -0.7874 0.4064)
			(stroke
				(width 0.1524)
				(type default)
			)
			(layer "F.SilkS")
		)
		(fp_poly
			(pts
				(xy -0.508 0.2794) (xy -0.508 0.2286) (xy -0.635 0.2286) (xy -0.635 -0.254) (xy -0.5334 -0.254)
				(xy -0.5334 -0.2794) (xy 0.5334 -0.2794) (xy 0.5334 -0.254) (xy 0.635 -0.254) (xy 0.635 0.254) (xy 0.5334 0.254)
				(xy 0.5334 0.2794)
			)
			(stroke
				(width 0)
				(type default)
			)
			(fill no)
			(layer "F.CrtYd")
		)
		(pad "1" smd rect
			(at 0.40005 0)
			(size 0.4572 0.508)
			(layers "F.Cu" "F.Mask" "F.Paste")
			(net "PSU5_PS_KILL")
		)
		(pad "2" smd rect
			(at -0.40005 0)
			(size 0.4572 0.508)
			(layers "F.Cu" "F.Mask" "F.Paste")
			(net "P12V_STBY")
		)
	)
)
